(kicad_pcb
	(version 20260206)
	(generator "pcbnew")
	(generator_version "10.0")
	(general
		(thickness 1.6)
		(legacy_teardrops no)
	)
	(paper "A4")
	(title_block
		(title "9054_F0T_PDB_BD_GPU_F_V04_1213_1550_OCP.brd")
		(comment 1 "Grand Teton / footprints 314-319 of 608")
	)
	(layers
		(0 "F.Cu" signal "TOP")
		(4 "In1.Cu" signal "GND")
		(6 "In2.Cu" signal "IN1")
		(8 "In3.Cu" signal "GND1")
		(10 "In4.Cu" signal "VCC")
		(12 "In5.Cu" signal "VCC1")
		(14 "In6.Cu" signal "GND2")
		(16 "In7.Cu" signal "IN2")
		(18 "In8.Cu" signal "GND3")
		(2 "B.Cu" signal "BOTTOM")
		(9 "F.Adhes" user "F.Adhesive")
		(11 "B.Adhes" user "B.Adhesive")
		(13 "F.Paste" user "Package Geometry/Pastemask Top")
		(15 "B.Paste" user "Package Geometry/Pastemask Bottom")
		(5 "F.SilkS" user "Ref Des/Silkscreen Top")
		(7 "B.SilkS" user "Ref Des/Silkscreen Bottom")
		(1 "F.Mask" user "Board Geometry/Soldermask Top")
		(3 "B.Mask" user "Board Geometry/Soldermask Bottom")
		(17 "Dwgs.User" user "User.Drawings")
		(19 "Cmts.User" user "User.Comments")
		(21 "Eco1.User" user "User.Eco1")
		(23 "Eco2.User" user "User.Eco2")
		(25 "Edge.Cuts" user "Board Geometry/Outline")
		(27 "Margin" user)
		(31 "F.CrtYd" user "Package Geometry/Place Bound Top")
		(29 "B.CrtYd" user "Package Geometry/Place Bound Bottom")
		(35 "F.Fab" user "Ref Des/Assembly Top")
		(33 "B.Fab" user "Ref Des/Assembly Bottom")
	)
	(footprint ""
		(layer "F.Cu")
		(at 14.99997 -126.500128 180)
		(property "Reference" "H36"
			(at -2.58953 -5.762498 0)
			(unlocked yes)
			(layer "F.SilkS")
			(effects
				(font
					(size 0.7874 0.5842)
					(thickness 0.1524)
				)
				(justify left)
			)
		)
		(property "Value" ""
			(at 0 0 180)
			(layer "F.Fab")
			(effects
				(font
					(size 1.27 1.27)
				)
			)
		)
		(duplicate_pad_numbers_are_jumpers no)
		(pad "1" thru_hole circle
			(at 0 0 180)
			(size 10.16 10.16)
			(drill 6.4008
				(offset 0 0)
			)
			(layers "*.Cu" "*.Mask")
			(remove_unused_layers no)
			(net "GND")
			(clearance -1.6256)
			(padstack
				(mode front_inner_back)
				(layer "Inner"
					(shape circle)
					(size 10.16 10.16)
					(clearance -1.6256)
				)
				(layer "B.Cu"
					(shape oval)
					(size 10.0076 17.018)
					(offset 0 3.499866)
					(clearance -1.5494)
				)
			)
		)
	)
	(footprint ""
		(layer "F.Cu")
		(at 168.529 -80.264 -90)
		(property "Reference" "R5908"
			(at 0 0 270)
			(layer "F.SilkS")
			(hide yes)
			(effects
				(font
					(size 1.27 1.27)
				)
			)
		)
		(property "Value" ""
			(at 0 0 270)
			(layer "F.Fab")
			(effects
				(font
					(size 1.27 1.27)
				)
			)
		)
		(duplicate_pad_numbers_are_jumpers no)
		(fp_line
			(start -0.7874 0.4064)
			(end -0.7874 -0.4064)
			(stroke
				(width 0.1524)
				(type default)
			)
			(layer "F.SilkS")
		)
		(fp_line
			(start 0.7874 0.4064)
			(end -0.7874 0.4064)
			(stroke
				(width 0.1524)
				(type default)
			)
			(layer "F.SilkS")
		)
		(fp_line
			(start -0.7874 -0.4064)
			(end 0.7874 -0.4064)
			(stroke
				(width 0.1524)
				(type default)
			)
			(layer "F.SilkS")
		)
		(fp_line
			(start 0.7874 -0.4064)
			(end 0.7874 0.4064)
			(stroke
				(width 0.1524)
				(type default)
			)
			(layer "F.SilkS")
		)
		(fp_line
			(start -0.67945 0.3048)
			(end -0.67945 -0.305054)
			(stroke
				(width 0.1)
				(type default)
			)
			(layer "F.Fab")
		)
		(fp_line
			(start -0.12065 0.3048)
			(end -0.67945 0.3048)
			(stroke
				(width 0.1)
				(type default)
			)
			(layer "F.Fab")
		)
		(fp_line
			(start 0.120396 0.3048)
			(end 0.120396 0.2794)
			(stroke
				(width 0.1)
				(type default)
			)
			(layer "F.Fab")
		)
		(fp_line
			(start 0.67945 0.3048)
			(end 0.120396 0.3048)
			(stroke
				(width 0.1)
				(type default)
			)
			(layer "F.Fab")
		)
		(fp_line
			(start -0.12065 0.2794)
			(end -0.12065 0.3048)
			(stroke
				(width 0.1)
				(type default)
			)
			(layer "F.Fab")
		)
		(fp_line
			(start 0.120396 0.2794)
			(end -0.12065 0.2794)
			(stroke
				(width 0.1)
				(type default)
			)
			(layer "F.Fab")
		)
		(fp_line
			(start -0.12065 -0.2794)
			(end 0.12065 -0.2794)
			(stroke
				(width 0.1)
				(type default)
			)
			(layer "F.Fab")
		)
		(fp_line
			(start 0.12065 -0.2794)
			(end 0.12065 -0.3048)
			(stroke
				(width 0.1)
				(type default)
			)
			(layer "F.Fab")
		)
		(fp_line
			(start 0.12065 -0.3048)
			(end 0.67945 -0.3048)
			(stroke
				(width 0.1)
				(type default)
			)
			(layer "F.Fab")
		)
		(fp_line
			(start 0.67945 -0.3048)
			(end 0.67945 0.3048)
			(stroke
				(width 0.1)
				(type default)
			)
			(layer "F.Fab")
		)
		(fp_line
			(start -0.67945 -0.305054)
			(end -0.12065 -0.305054)
			(stroke
				(width 0.1)
				(type default)
			)
			(layer "F.Fab")
		)
		(fp_line
			(start -0.12065 -0.305054)
			(end -0.12065 -0.2794)
			(stroke
				(width 0.1)
				(type default)
			)
			(layer "F.Fab")
		)
		(pad "1" smd circle
			(at -0.40005 0 270)
			(size 0 0)
			(layers "F.Cu" "F.Mask" "F.Paste")
			(net "FM_HS2_EN_BUSBAR")
		)
		(pad "2" smd circle
			(at 0.40005 0 270)
			(size 0 0)
			(layers "F.Cu" "F.Mask" "F.Paste")
			(net "GND")
		)
	)
	(footprint ""
		(layer "F.Cu")
		(at 81.661 -17.907 -90)
		(property "Reference" "R77"
			(at 0 0 270)
			(layer "F.SilkS")
			(hide yes)
			(effects
				(font
					(size 1.27 1.27)
				)
			)
		)
		(property "Value" ""
			(at 0 0 270)
			(layer "F.Fab")
			(effects
				(font
					(size 1.27 1.27)
				)
			)
		)
		(duplicate_pad_numbers_are_jumpers no)
		(fp_line
			(start -0.7874 0.4064)
			(end -0.7874 -0.4064)
			(stroke
				(width 0.1524)
				(type default)
			)
			(layer "F.SilkS")
		)
		(fp_line
			(start 0.7874 0.4064)
			(end -0.7874 0.4064)
			(stroke
				(width 0.1524)
				(type default)
			)
			(layer "F.SilkS")
		)
		(fp_line
			(start -0.7874 -0.4064)
			(end 0.7874 -0.4064)
			(stroke
				(width 0.1524)
				(type default)
			)
			(layer "F.SilkS")
		)
		(fp_line
			(start 0.7874 -0.4064)
			(end 0.7874 0.4064)
			(stroke
				(width 0.1524)
				(type default)
			)
			(layer "F.SilkS")
		)
		(fp_line
			(start -0.67945 0.3048)
			(end -0.67945 -0.305054)
			(stroke
				(width 0.1)
				(type default)
			)
			(layer "F.Fab")
		)
		(fp_line
			(start -0.12065 0.3048)
			(end -0.67945 0.3048)
			(stroke
				(width 0.1)
				(type default)
			)
			(layer "F.Fab")
		)
		(fp_line
			(start 0.120396 0.3048)
			(end 0.120396 0.2794)
			(stroke
				(width 0.1)
				(type default)
			)
			(layer "F.Fab")
		)
		(fp_line
			(start 0.67945 0.3048)
			(end 0.120396 0.3048)
			(stroke
				(width 0.1)
				(type default)
			)
			(layer "F.Fab")
		)
		(fp_line
			(start -0.12065 0.2794)
			(end -0.12065 0.3048)
			(stroke
				(width 0.1)
				(type default)
			)
			(layer "F.Fab")
		)
		(fp_line
			(start 0.120396 0.2794)
			(end -0.12065 0.2794)
			(stroke
				(width 0.1)
				(type default)
			)
			(layer "F.Fab")
		)
		(fp_line
			(start -0.12065 -0.2794)
			(end 0.12065 -0.2794)
			(stroke
				(width 0.1)
				(type default)
			)
			(layer "F.Fab")
		)
		(fp_line
			(start 0.12065 -0.2794)
			(end 0.12065 -0.3048)
			(stroke
				(width 0.1)
				(type default)
			)
			(layer "F.Fab")
		)
		(fp_line
			(start 0.12065 -0.3048)
			(end 0.67945 -0.3048)
			(stroke
				(width 0.1)
				(type default)
			)
			(layer "F.Fab")
		)
		(fp_line
			(start 0.67945 -0.3048)
			(end 0.67945 0.3048)
			(stroke
				(width 0.1)
				(type default)
			)
			(layer "F.Fab")
		)
		(fp_line
			(start -0.67945 -0.305054)
			(end -0.12065 -0.305054)
			(stroke
				(width 0.1)
				(type default)
			)
			(layer "F.Fab")
		)
		(fp_line
			(start -0.12065 -0.305054)
			(end -0.12065 -0.2794)
			(stroke
				(width 0.1)
				(type default)
			)
			(layer "F.Fab")
		)
		(pad "1" smd circle
			(at -0.40005 0 270)
			(size 0 0)
			(layers "F.Cu" "F.Mask" "F.Paste")
			(net "SMB_PDB_FAN_1_SDA")
		)
		(pad "2" smd circle
			(at 0.40005 0 270)
			(size 0 0)
			(layers "F.Cu" "F.Mask" "F.Paste")
			(net "SMB_PDB_FAN_1_R_SDA")
		)
	)
	(footprint ""
		(layer "F.Cu")
		(at 238.810038 -22.474936)
		(property "Reference" "H35"
			(at -1.9812 -4.079748 0)
			(unlocked yes)
			(layer "B.SilkS")
			(effects
				(font
					(size 0.7874 0.5842)
					(thickness 0.1524)
				)
				(justify left mirror)
			)
		)
		(property "Value" ""
			(at 0 0 0)
			(layer "F.Fab")
			(effects
				(font
					(size 1.27 1.27)
				)
			)
		)
		(duplicate_pad_numbers_are_jumpers no)
		(pad "1" thru_hole circle
			(at 0 0)
			(size 8.001 8.001)
			(drill 4.2418)
			(layers "*.Cu" "*.Mask")
			(remove_unused_layers no)
			(net "TP_H35")
			(clearance -1.6256)
			(padstack
				(mode front_inner_back)
				(layer "Inner"
					(shape circle)
					(size 6.0198 6.0198)
					(clearance -0.635)
				)
				(layer "B.Cu"
					(shape circle)
					(size 8.001 8.001)
					(clearance -1.6256)
				)
			)
		)
		(zone
			(layers "F.Cu" "B.Cu" "In1.Cu" "In2.Cu" "In3.Cu" "In4.Cu" "In5.Cu" "In6.Cu"
				"In7.Cu" "In8.Cu"
			)
			(hatch none 0.5)
			(connect_pads
				(clearance 0)
			)
			(min_thickness 0.25)
			(keepout
				(tracks not_allowed)
				(vias allowed)
				(pads allowed)
				(copperpour not_allowed)
				(footprints allowed)
			)
			(placement
				(enabled no)
				(sheetname "")
			)
			(fill
				(thermal_gap 0.5)
				(thermal_bridge_width 0.5)
				(island_removal_mode 0)
			)
			(polygon
				(pts
					(arc
						(start 242.320064 -22.474936)
						(mid 235.300012 -22.474936)
						(end 242.320064 -22.474936)
					)
				)
			)
		)
	)
	(footprint ""
		(layer "F.Cu")
		(at 222.6564 -97.028 180)
		(property "Reference" "PR97"
			(at 0 0 180)
			(layer "F.SilkS")
			(hide yes)
			(effects
				(font
					(size 1.27 1.27)
				)
			)
		)
		(property "Value" ""
			(at 0 0 180)
			(layer "F.Fab")
			(effects
				(font
					(size 1.27 1.27)
				)
			)
		)
		(duplicate_pad_numbers_are_jumpers no)
		(fp_line
			(start 0.7874 0.4064)
			(end -0.7874 0.4064)
			(stroke
				(width 0.1524)
				(type default)
			)
			(layer "F.SilkS")
		)
		(fp_line
			(start 0.7874 -0.4064)
			(end 0.7874 0.4064)
			(stroke
				(width 0.1524)
				(type default)
			)
			(layer "F.SilkS")
		)
		(fp_line
			(start -0.7874 0.4064)
			(end -0.7874 -0.4064)
			(stroke
				(width 0.1524)
				(type default)
			)
			(layer "F.SilkS")
		)
		(fp_line
			(start -0.7874 -0.4064)
			(end 0.7874 -0.4064)
			(stroke
				(width 0.1524)
				(type default)
			)
			(layer "F.SilkS")
		)
		(fp_line
			(start 0.67945 0.3048)
			(end 0.120396 0.3048)
			(stroke
				(width 0.1)
				(type default)
			)
			(layer "F.Fab")
		)
		(fp_line
			(start 0.67945 -0.3048)
			(end 0.67945 0.3048)
			(stroke
				(width 0.1)
				(type default)
			)
			(layer "F.Fab")
		)
		(fp_line
			(start 0.12065 -0.2794)
			(end 0.12065 -0.3048)
			(stroke
				(width 0.1)
				(type default)
			)
			(layer "F.Fab")
		)
		(fp_line
			(start 0.12065 -0.3048)
			(end 0.67945 -0.3048)
			(stroke
				(width 0.1)
				(type default)
			)
			(layer "F.Fab")
		)
		(fp_line
			(start 0.120396 0.3048)
			(end 0.120396 0.2794)
			(stroke
				(width 0.1)
				(type default)
			)
			(layer "F.Fab")
		)
		(fp_line
			(start 0.120396 0.2794)
			(end -0.12065 0.2794)
			(stroke
				(width 0.1)
				(type default)
			)
			(layer "F.Fab")
		)
		(fp_line
			(start -0.12065 0.3048)
			(end -0.67945 0.3048)
			(stroke
				(width 0.1)
				(type default)
			)
			(layer "F.Fab")
		)
		(fp_line
			(start -0.12065 0.2794)
			(end -0.12065 0.3048)
			(stroke
				(width 0.1)
				(type default)
			)
			(layer "F.Fab")
		)
		(fp_line
			(start -0.12065 -0.2794)
			(end 0.12065 -0.2794)
			(stroke
				(width 0.1)
				(type default)
			)
			(layer "F.Fab")
		)
		(fp_line
			(start -0.12065 -0.305054)
			(end -0.12065 -0.2794)
			(stroke
				(width 0.1)
				(type default)
			)
			(layer "F.Fab")
		)
		(fp_line
			(start -0.67945 0.3048)
			(end -0.67945 -0.305054)
			(stroke
				(width 0.1)
				(type default)
			)
			(layer "F.Fab")
		)
		(fp_line
			(start -0.67945 -0.305054)
			(end -0.12065 -0.305054)
			(stroke
				(width 0.1)
				(type default)
			)
			(layer "F.Fab")
		)
		(pad "1" smd circle
			(at -0.40005 0 180)
			(size 0 0)
			(layers "F.Cu" "F.Mask" "F.Paste")
			(net "SMB_P52V_PDB_SDA")
		)
		(pad "2" smd circle
			(at 0.40005 0 180)
			(size 0 0)
			(layers "F.Cu" "F.Mask" "F.Paste")
			(net "SMB_P52V_PDB_DEBUG_SDA")
		)
	)
	(footprint ""
		(layer "F.Cu")
		(at 442.595 -30.353)
		(property "Reference" "U18"
			(at -5.6515 -4.78663 0)
			(unlocked yes)
			(layer "F.SilkS")
			(effects
				(font
					(size 0.7874 0.5842)
					(thickness 0.1524)
				)
				(justify left)
			)
		)
		(property "Value" ""
			(at 0 0 0)
			(layer "F.Fab")
			(effects
				(font
					(size 1.27 1.27)
				)
			)
		)
		(duplicate_pad_numbers_are_jumpers no)
		(fp_line
			(start -1.4224 -4.3688)
			(end -0.4572 -4.3688)
			(stroke
				(width 0.1524)
				(type default)
			)
			(layer "F.SilkS")
		)
		(fp_line
			(start -1.4224 4.3688)
			(end -1.4224 -4.3688)
			(stroke
				(width 0.1524)
				(type default)
			)
			(layer "F.SilkS")
		)
		(fp_line
			(start -0.4572 -4.3688)
			(end 0 -3.9116)
			(stroke
				(width 0.1524)
				(type default)
			)
			(layer "F.SilkS")
		)
		(fp_line
			(start 0 -3.9116)
			(end 0.4572 -4.3688)
			(stroke
				(width 0.1524)
				(type default)
			)
			(layer "F.SilkS")
		)
		(fp_line
			(start 0.4572 -4.3688)
			(end 1.4224 -4.3688)
			(stroke
				(width 0.1524)
				(type default)
			)
			(layer "F.SilkS")
		)
		(fp_line
			(start 1.4224 -4.3688)
			(end 1.4224 4.3688)
			(stroke
				(width 0.1524)
				(type default)
			)
			(layer "F.SilkS")
		)
		(fp_line
			(start 1.4224 4.3688)
			(end -1.4224 4.3688)
			(stroke
				(width 0.1524)
				(type default)
			)
			(layer "F.SilkS")
		)
		(fp_poly
			(pts
				(xy -2.728214 -4.318) (xy -3.109214 -5.08) (xy -2.347214 -5.08)
			)
			(stroke
				(width 0)
				(type default)
			)
			(fill yes)
			(layer "F.SilkS")
		)
		(fp_line
			(start -2.6416 -4.141216)
			(end -2.0066 -4.141216)
			(stroke
				(width 0.1)
				(type default)
			)
			(layer "F.Fab")
		)
		(fp_line
			(start -2.6416 4.140708)
			(end -2.6416 -4.141216)
			(stroke
				(width 0.1)
				(type default)
			)
			(layer "F.Fab")
		)
		(fp_line
			(start -2.0066 -4.3688)
			(end 2.0066 -4.3688)
			(stroke
				(width 0.1)
				(type default)
			)
			(layer "F.Fab")
		)
		(fp_line
			(start -2.0066 -4.141216)
			(end -2.0066 -4.3688)
			(stroke
				(width 0.1)
				(type default)
			)
			(layer "F.Fab")
		)
		(fp_line
			(start -2.0066 4.140708)
			(end -2.6416 4.140708)
			(stroke
				(width 0.1)
				(type default)
			)
			(layer "F.Fab")
		)
		(fp_line
			(start -2.0066 4.3688)
			(end -2.0066 4.140708)
			(stroke
				(width 0.1)
				(type default)
			)
			(layer "F.Fab")
		)
		(fp_line
			(start 2.0066 -4.3688)
			(end 2.0066 -4.143756)
			(stroke
				(width 0.1)
				(type default)
			)
			(layer "F.Fab")
		)
		(fp_line
			(start 2.0066 -4.143756)
			(end 2.6416 -4.143756)
			(stroke
				(width 0.1)
				(type default)
			)
			(layer "F.Fab")
		)
		(fp_line
			(start 2.0066 4.139438)
			(end 2.0066 4.3688)
			(stroke
				(width 0.1)
				(type default)
			)
			(layer "F.Fab")
		)
		(fp_line
			(start 2.0066 4.3688)
			(end -2.0066 4.3688)
			(stroke
				(width 0.1)
				(type default)
			)
			(layer "F.Fab")
		)
		(fp_line
			(start 2.6416 -4.143756)
			(end 2.6416 4.139438)
			(stroke
				(width 0.1)
				(type default)
			)
			(layer "F.Fab")
		)
		(fp_line
			(start 2.6416 4.139438)
			(end 2.0066 4.139438)
			(stroke
				(width 0.1)
				(type default)
			)
			(layer "F.Fab")
		)
		(fp_poly
			(pts
				(xy -3.6576 -3.850386) (xy -4.4196 -3.469386) (xy -4.4196 -4.231386)
			)
			(stroke
				(width 0)
				(type default)
			)
			(fill yes)
			(layer "F.Fab")
		)
		(pad "1" smd rect
			(at -2.6416 -3.81 270)
			(size 0.5588 1.7272)
			(layers "F.Cu" "F.Mask" "F.Paste")
			(net "PD_9543_FAN_A0")
		)
		(pad "2" smd rect
			(at -2.6416 -2.54 270)
			(size 0.5588 1.7272)
			(layers "F.Cu" "F.Mask" "F.Paste")
			(net "PD_9543_FAN_A1")
		)
		(pad "3" smd rect
			(at -2.6416 -1.27 270)
			(size 0.5588 1.7272)
			(layers "F.Cu" "F.Mask" "F.Paste")
			(net "RST_SMB_PDB_BUF_N")
		)
		(pad "4" smd rect
			(at -2.6416 0 270)
			(size 0.5588 1.7272)
			(layers "F.Cu" "F.Mask" "F.Paste")
			(net "PU_9543_0_FAN")
		)
		(pad "5" smd rect
			(at -2.6416 1.27 270)
			(size 0.5588 1.7272)
			(layers "F.Cu" "F.Mask" "F.Paste")
			(net "SMB_PDB_FAN_0_SDA")
		)
		(pad "6" smd rect
			(at -2.6416 2.54 270)
			(size 0.5588 1.7272)
			(layers "F.Cu" "F.Mask" "F.Paste")
			(net "SMB_PDB_FAN_0_SCL")
		)
		(pad "7" smd rect
			(at -2.6416 3.81 270)
			(size 0.5588 1.7272)
			(layers "F.Cu" "F.Mask" "F.Paste")
			(net "GND")
		)
		(pad "8" smd rect
			(at 2.6416 3.81 270)
			(size 0.5588 1.7272)
			(layers "F.Cu" "F.Mask" "F.Paste")
			(net "PU_9543_1_FAN")
		)
		(pad "9" smd rect
			(at 2.6416 2.54 270)
			(size 0.5588 1.7272)
			(layers "F.Cu" "F.Mask" "F.Paste")
			(net "SMB_PDB_FAN_1_SDA")
		)
		(pad "10" smd rect
			(at 2.6416 1.27 270)
			(size 0.5588 1.7272)
			(layers "F.Cu" "F.Mask" "F.Paste")
			(net "SMB_PDB_FAN_1_SCL")
		)
		(pad "11" smd rect
			(at 2.6416 0 270)
			(size 0.5588 1.7272)
			(layers "F.Cu" "F.Mask" "F.Paste")
			(net "TP_9543_FAN_INT_N")
		)
		(pad "12" smd rect
			(at 2.6416 -1.27 270)
			(size 0.5588 1.7272)
			(layers "F.Cu" "F.Mask" "F.Paste")
			(net "SMB_FAN_MUX_SCL")
		)
		(pad "13" smd rect
			(at 2.6416 -2.54 270)
			(size 0.5588 1.7272)
			(layers "F.Cu" "F.Mask" "F.Paste")
			(net "SMB_FAN_MUX_SDA")
		)
		(pad "14" smd rect
			(at 2.6416 -3.81 270)
			(size 0.5588 1.7272)
			(layers "F.Cu" "F.Mask" "F.Paste")
			(net "P3V3_AUX")
		)
	)
)
